(kicad_pcb
	(version 20260206)
	(generator "pcbnew")
	(generator_version "10.0")
	(general
		(thickness 1.6)
		(legacy_teardrops no)
	)
	(paper "A4")
	(title_block
		(title "Wiwynn_Tioga_Pass_MB.brd")
		(comment 1 "Tioga Pass / footprints 709-712 of 4770")
	)
	(layers
		(0 "F.Cu" signal "TOP")
		(4 "In1.Cu" signal "L2GND")
		(6 "In2.Cu" signal "L3")
		(8 "In3.Cu" signal "L4GND")
		(10 "In4.Cu" signal "L5")
		(12 "In5.Cu" signal "L6GND")
		(14 "In6.Cu" signal "L7VCC")
		(16 "In7.Cu" signal "L8VCC")
		(18 "In8.Cu" signal "L9GND")
		(20 "In9.Cu" signal "L10")
		(22 "In10.Cu" signal "L11GND")
		(24 "In11.Cu" signal "L12")
		(26 "In12.Cu" signal "L13GND")
		(2 "B.Cu" signal "BOTTOM")
		(9 "F.Adhes" user "F.Adhesive")
		(11 "B.Adhes" user "B.Adhesive")
		(13 "F.Paste" user "Package Geometry/Pastemask Top")
		(15 "B.Paste" user "Package Geometry/Pastemask Bottom")
		(5 "F.SilkS" user "Ref Des/Silkscreen Top")
		(7 "B.SilkS" user "Ref Des/Silkscreen Bottom")
		(1 "F.Mask" user "Board Geometry/Soldermask Top")
		(3 "B.Mask" user "Board Geometry/Soldermask Bottom")
		(17 "Dwgs.User" user "User.Drawings")
		(19 "Cmts.User" user "User.Comments")
		(21 "Eco1.User" user "User.Eco1")
		(23 "Eco2.User" user "User.Eco2")
		(25 "Edge.Cuts" user "Board Geometry/Outline")
		(27 "Margin" user)
		(31 "F.CrtYd" user "Package Geometry/Place Bound Top")
		(29 "B.CrtYd" user "Package Geometry/Place Bound Bottom")
		(35 "F.Fab" user "Ref Des/Assembly Top")
		(33 "B.Fab" user "Ref Des/Assembly Bottom")
	)
	(footprint ""
		(layer "F.Cu")
		(at 402.830792 -10.917936)
		(property "Reference" "C8G3"
			(at 0 0 0)
			(layer "F.SilkS")
			(hide yes)
			(effects
				(font
					(size 1.27 1.27)
				)
			)
		)
		(property "Value" ""
			(at 0 0 0)
			(layer "F.Fab")
			(effects
				(font
					(size 1.27 1.27)
				)
			)
		)
		(duplicate_pad_numbers_are_jumpers no)
		(fp_rect
			(start -0.3048 0.9906)
			(end 0.3048 -0.1016)
			(stroke
				(width 0)
				(type default)
			)
			(fill no)
			(layer "F.CrtYd")
		)
		(fp_line
			(start -0.3048 -0.1016)
			(end -0.3048 0.9906)
			(stroke
				(width 0.1)
				(type default)
			)
			(layer "F.Fab")
		)
		(fp_line
			(start -0.3048 0.9906)
			(end 0.3048 0.9906)
			(stroke
				(width 0.1)
				(type default)
			)
			(layer "F.Fab")
		)
		(fp_line
			(start 0.3048 -0.1016)
			(end -0.3048 -0.1016)
			(stroke
				(width 0.1)
				(type default)
			)
			(layer "F.Fab")
		)
		(fp_line
			(start 0.3048 0.9906)
			(end 0.3048 -0.1016)
			(stroke
				(width 0.1)
				(type default)
			)
			(layer "F.Fab")
		)
		(pad "1" smd rect
			(at 0 0)
			(size 0.508 0.508)
			(layers "F.Cu" "F.Mask" "F.Paste")
			(net "P3E_CPU0_PE2_SS_TXP<3>")
		)
		(pad "2" smd rect
			(at 0 0.889)
			(size 0.508 0.508)
			(layers "F.Cu" "F.Mask" "F.Paste")
			(net "P3E_CPU0_PE2_SS_C_TXP<3>")
		)
		(zone
			(layer "F.Cu")
			(hatch none 0.5)
			(connect_pads
				(clearance 0)
			)
			(min_thickness 0.25)
			(keepout
				(tracks not_allowed)
				(vias allowed)
				(pads allowed)
				(copperpour not_allowed)
				(footprints allowed)
			)
			(placement
				(enabled no)
				(sheetname "")
			)
			(fill
				(thermal_gap 0.5)
				(thermal_bridge_width 0.5)
				(island_removal_mode 0)
			)
			(polygon
				(pts
					(xy 402.576792 -10.282936) (xy 403.084792 -10.282936) (xy 403.084792 -10.663936) (xy 402.576792 -10.663936)
				)
			)
		)
		(zone
			(layer "F.Cu")
			(hatch none 0.5)
			(connect_pads
				(clearance 0)
			)
			(min_thickness 0.25)
			(keepout
				(tracks allowed)
				(vias not_allowed)
				(pads allowed)
				(copperpour not_allowed)
				(footprints allowed)
			)
			(placement
				(enabled no)
				(sheetname "")
			)
			(fill
				(thermal_gap 0.5)
				(thermal_bridge_width 0.5)
				(island_removal_mode 0)
			)
			(polygon
				(pts
					(xy 402.576792 -10.282936) (xy 403.084792 -10.282936) (xy 403.084792 -10.663936) (xy 402.576792 -10.663936)
				)
			)
		)
	)
	(footprint ""
		(layer "F.Cu")
		(at 271.898872 -77.636116)
		(property "Reference" "C5D35"
			(at 0 0 0)
			(layer "F.SilkS")
			(hide yes)
			(effects
				(font
					(size 1.27 1.27)
				)
			)
		)
		(property "Value" ""
			(at 0 0 0)
			(layer "F.Fab")
			(effects
				(font
					(size 1.27 1.27)
				)
			)
		)
		(duplicate_pad_numbers_are_jumpers no)
		(fp_poly
			(pts
				(xy -0.4953 -0.2032) (xy 0.4953 -0.2032) (xy 0.4953 1.6002) (xy -0.4953 1.6002)
			)
			(stroke
				(width 0)
				(type default)
			)
			(fill no)
			(layer "F.CrtYd")
		)
		(fp_line
			(start -0.4953 -0.2032)
			(end 0.4953 -0.2032)
			(stroke
				(width 0.1)
				(type default)
			)
			(layer "F.Fab")
		)
		(fp_line
			(start -0.4953 1.6002)
			(end -0.4953 -0.2032)
			(stroke
				(width 0.1)
				(type default)
			)
			(layer "F.Fab")
		)
		(fp_line
			(start 0.4953 -0.2032)
			(end 0.4953 1.6002)
			(stroke
				(width 0.1)
				(type default)
			)
			(layer "F.Fab")
		)
		(fp_line
			(start 0.4953 1.6002)
			(end -0.4953 1.6002)
			(stroke
				(width 0.1)
				(type default)
			)
			(layer "F.Fab")
		)
		(pad "1" smd rect
			(at 0 0)
			(size 0.762 0.889)
			(layers "F.Cu" "F.Mask" "F.Paste")
			(net "PVCCMCP_CPU0")
		)
		(pad "2" smd rect
			(at 0 1.397)
			(size 0.762 0.889)
			(layers "F.Cu" "F.Mask" "F.Paste")
			(net "GND")
		)
		(zone
			(layer "F.Cu")
			(hatch none 0.5)
			(connect_pads
				(clearance 0)
			)
			(min_thickness 0.25)
			(keepout
				(tracks not_allowed)
				(vias allowed)
				(pads allowed)
				(copperpour not_allowed)
				(footprints allowed)
			)
			(placement
				(enabled no)
				(sheetname "")
			)
			(fill
				(thermal_gap 0.5)
				(thermal_bridge_width 0.5)
				(island_removal_mode 0)
			)
			(polygon
				(pts
					(xy 271.517872 -77.191616) (xy 272.279872 -77.191616) (xy 272.279872 -76.683616) (xy 271.517872 -76.683616)
				)
			)
		)
	)
	(footprint ""
		(layer "F.Cu")
		(at 124.222002 -77.449934 180)
		(property "Reference" "XRU2"
			(at -17.763998 32.632396 0)
			(unlocked yes)
			(layer "F.SilkS")
			(effects
				(font
					(size 0.7874 0.5842)
					(thickness 0.1524)
				)
				(justify left)
			)
		)
		(property "Value" ""
			(at 0 0 180)
			(layer "F.Fab")
			(effects
				(font
					(size 1.27 1.27)
				)
			)
		)
		(duplicate_pad_numbers_are_jumpers no)
		(fp_line
			(start 19.221958 -10.649966)
			(end 19.221958 -29.399992)
			(stroke
				(width 0.1524)
				(type default)
			)
			(layer "F.SilkS")
		)
		(fp_line
			(start 19.221958 -29.399992)
			(end 18.62201 -29.399992)
			(stroke
				(width 0.1524)
				(type default)
			)
			(layer "F.SilkS")
		)
		(fp_line
			(start 18.62201 28.599892)
			(end 18.62201 8.850122)
			(stroke
				(width 0.1524)
				(type default)
			)
			(layer "F.SilkS")
		)
		(fp_line
			(start 18.62201 27.599894)
			(end 18.62201 8.850122)
			(stroke
				(width 0.1524)
				(type default)
			)
			(layer "F.SilkS")
		)
		(fp_line
			(start 18.62201 8.850122)
			(end 12.761976 8.850122)
			(stroke
				(width 0.1524)
				(type default)
			)
			(layer "F.SilkS")
		)
		(fp_line
			(start 18.62201 8.850122)
			(end 12.761976 8.850122)
			(stroke
				(width 0.1524)
				(type default)
			)
			(layer "F.SilkS")
		)
		(fp_line
			(start 18.62201 -29.399992)
			(end 18.62201 -30.39999)
			(stroke
				(width 0.1524)
				(type default)
			)
			(layer "F.SilkS")
		)
		(fp_line
			(start 18.62201 -30.39999)
			(end 17.622012 -30.39999)
			(stroke
				(width 0.1524)
				(type default)
			)
			(layer "F.SilkS")
		)
		(fp_line
			(start 17.622012 28.599892)
			(end 18.62201 28.599892)
			(stroke
				(width 0.1524)
				(type default)
			)
			(layer "F.SilkS")
		)
		(fp_line
			(start 17.622012 27.599894)
			(end 17.622012 28.599892)
			(stroke
				(width 0.1524)
				(type default)
			)
			(layer "F.SilkS")
		)
		(fp_line
			(start 17.622012 -29.399992)
			(end -14.777974 -29.399992)
			(stroke
				(width 0.1524)
				(type default)
			)
			(layer "F.SilkS")
		)
		(fp_line
			(start 17.622012 -30.39999)
			(end 17.622012 -29.399992)
			(stroke
				(width 0.1524)
				(type default)
			)
			(layer "F.SilkS")
		)
		(fp_line
			(start 12.761976 8.850122)
			(end 6.171946 4.890008)
			(stroke
				(width 0.1524)
				(type default)
			)
			(layer "F.SilkS")
		)
		(fp_line
			(start 12.761976 8.850122)
			(end 6.171946 4.890008)
			(stroke
				(width 0.1524)
				(type default)
			)
			(layer "F.SilkS")
		)
		(fp_line
			(start 12.761976 -10.649966)
			(end 19.221958 -10.649966)
			(stroke
				(width 0.1524)
				(type default)
			)
			(layer "F.SilkS")
		)
		(fp_line
			(start 12.761976 -10.649966)
			(end 19.221958 -10.649966)
			(stroke
				(width 0.1524)
				(type default)
			)
			(layer "F.SilkS")
		)
		(fp_line
			(start 6.171946 4.890008)
			(end 6.171946 -6.690106)
			(stroke
				(width 0.1524)
				(type default)
			)
			(layer "F.SilkS")
		)
		(fp_line
			(start 6.171946 4.890008)
			(end 6.171946 -6.690106)
			(stroke
				(width 0.1524)
				(type default)
			)
			(layer "F.SilkS")
		)
		(fp_line
			(start 6.171946 -6.690106)
			(end 12.761976 -10.649966)
			(stroke
				(width 0.1524)
				(type default)
			)
			(layer "F.SilkS")
		)
		(fp_line
			(start 6.171946 -6.690106)
			(end 12.761976 -10.649966)
			(stroke
				(width 0.1524)
				(type default)
			)
			(layer "F.SilkS")
		)
		(fp_line
			(start -14.777974 30.150054)
			(end -14.777974 27.599894)
			(stroke
				(width 0.1524)
				(type default)
			)
			(layer "F.SilkS")
		)
		(fp_line
			(start -14.777974 27.599894)
			(end 17.622012 27.599894)
			(stroke
				(width 0.1524)
				(type default)
			)
			(layer "F.SilkS")
		)
		(fp_line
			(start -14.777974 -29.399992)
			(end -14.777974 -31.949898)
			(stroke
				(width 0.1524)
				(type default)
			)
			(layer "F.SilkS")
		)
		(fp_line
			(start -14.777974 -31.949898)
			(end -21.77796 -31.949898)
			(stroke
				(width 0.1524)
				(type default)
			)
			(layer "F.SilkS")
		)
		(fp_line
			(start -17.777968 2.100072)
			(end -18.278094 2.100072)
			(stroke
				(width 0.1524)
				(type default)
			)
			(layer "F.SilkS")
		)
		(fp_line
			(start -17.777968 -3.899916)
			(end -17.777968 2.100072)
			(stroke
				(width 0.1524)
				(type default)
			)
			(layer "F.SilkS")
		)
		(fp_line
			(start -18.278094 3.599942)
			(end -21.77796 7.100062)
			(stroke
				(width 0.1524)
				(type default)
			)
			(layer "F.SilkS")
		)
		(fp_line
			(start -18.278094 2.100072)
			(end -18.278094 3.599942)
			(stroke
				(width 0.1524)
				(type default)
			)
			(layer "F.SilkS")
		)
		(fp_line
			(start -18.278094 -3.899916)
			(end -17.777968 -3.899916)
			(stroke
				(width 0.1524)
				(type default)
			)
			(layer "F.SilkS")
		)
		(fp_line
			(start -18.278094 -5.40004)
			(end -18.278094 -3.899916)
			(stroke
				(width 0.1524)
				(type default)
			)
			(layer "F.SilkS")
		)
		(fp_line
			(start -21.77796 30.150054)
			(end -14.777974 30.150054)
			(stroke
				(width 0.1524)
				(type default)
			)
			(layer "F.SilkS")
		)
		(fp_line
			(start -21.77796 7.100062)
			(end -21.77796 30.150054)
			(stroke
				(width 0.1524)
				(type default)
			)
			(layer "F.SilkS")
		)
		(fp_line
			(start -21.77796 -8.899906)
			(end -18.278094 -5.40004)
			(stroke
				(width 0.1524)
				(type default)
			)
			(layer "F.SilkS")
		)
		(fp_line
			(start -21.77796 -31.949898)
			(end -21.77796 -8.899906)
			(stroke
				(width 0.1524)
				(type default)
			)
			(layer "F.SilkS")
		)
		(fp_circle
			(center -28.829 -29.215334)
			(end -28.956 -29.215334)
			(stroke
				(width 0.254)
				(type default)
			)
			(fill no)
			(layer "F.SilkS")
		)
		(fp_poly
			(pts
				(xy -21.762212 30.150054) (xy -14.777974 30.150054) (xy -14.777974 27.599894) (xy 17.622012 27.599894)
				(xy 17.622012 28.599892) (xy 18.62201 28.599892) (xy 18.62201 8.850122) (xy 12.761976 8.850122)
				(xy 6.171946 4.890008) (xy 6.171946 -6.690106) (xy 12.761976 -10.649966) (xy 19.221958 -10.649966)
				(xy 19.221958 -29.399992) (xy 18.62201 -29.399992) (xy 18.62201 -30.39999) (xy 17.622012 -30.39999)
				(xy 17.622012 -29.399992) (xy -14.777974 -29.399992) (xy -14.777974 -31.949898) (xy -21.77796 -31.949898)
				(xy -21.77796 -8.899906) (xy -18.278094 -5.40004) (xy -18.278094 -3.899916) (xy -17.777968 -3.899916)
				(xy -17.777968 2.100072) (xy -18.278094 2.100072) (xy -18.278094 3.599942) (xy -21.77796 7.100062)
				(xy -21.77796 15.059406) (xy -20.051776 15.059406) (xy -20.048728 15.001748) (xy -20.04441 14.966442)
				(xy -20.036282 14.912086) (xy -20.02536 14.859762) (xy -20.007326 14.788134) (xy -19.98345 14.720062)
				(xy -19.96821 14.680692) (xy -19.937222 14.614144) (xy -19.910552 14.565376) (xy -19.878294 14.512544)
				(xy -19.833082 14.449044) (xy -19.790918 14.396466) (xy -19.746468 14.348714) (xy -19.70151 14.305026)
				(xy -19.629628 14.236954) (xy -19.548856 14.18336) (xy -19.442684 14.125956) (xy -19.368516 14.092936)
				(xy -19.202654 14.039342) (xy -19.046698 14.018514) (xy -18.893282 14.020546) (xy -18.758662 14.041882)
				(xy -18.615152 14.083792) (xy -18.402554 14.173962) (xy -18.269712 14.279118) (xy -18.178018 14.370558)
				(xy -18.112232 14.437614) (xy -18.027396 14.586204) (xy -17.924272 14.817598) (xy -17.897348 15.018766)
				(xy -17.888458 15.160498) (xy -17.906238 15.300198) (xy -17.959832 15.489936) (xy -18.057114 15.682976)
				(xy -18.231358 15.893034) (xy -18.479008 16.060928) (xy -18.689574 16.13916) (xy -18.864834 16.174466)
				(xy -19.001994 16.17726) (xy -19.118326 16.169894) (xy -19.228816 16.147542) (xy -19.45767 16.08074)
				(xy -19.611086 15.978886) (xy -19.714972 15.893034) (xy -19.798792 15.807182) (xy -19.89709 15.676372)
				(xy -19.983196 15.507716) (xy -20.0279 15.380462) (xy -20.056856 15.181834) (xy -20.051776 15.059914)
				(xy -21.77796 15.059914)
			)
			(stroke
				(width 0)
				(type default)
			)
			(fill no)
			(layer "F.CrtYd")
		)
		(fp_line
			(start -14.777974 30.150054)
			(end -21.77796 30.150054)
			(stroke
				(width 0.1)
				(type default)
			)
			(layer "F.Fab")
		)
		(fp_line
			(start -14.777974 27.420062)
			(end -14.777974 30.150054)
			(stroke
				(width 0.1)
				(type default)
			)
			(layer "F.Fab")
		)
		(fp_line
			(start -14.777974 -29.219906)
			(end -18.840958 -29.219906)
			(stroke
				(width 0.1)
				(type default)
			)
			(layer "F.Fab")
		)
		(fp_line
			(start -14.777974 -31.949898)
			(end -14.777974 -29.219906)
			(stroke
				(width 0.1)
				(type default)
			)
			(layer "F.Fab")
		)
		(fp_line
			(start -18.840958 27.420062)
			(end -14.777974 27.420062)
			(stroke
				(width 0.1)
				(type default)
			)
			(layer "F.Fab")
		)
		(fp_line
			(start -18.840958 22.649942)
			(end -18.840958 27.420062)
			(stroke
				(width 0.1)
				(type default)
			)
			(layer "F.Fab")
		)
		(fp_line
			(start -18.840958 22.649942)
			(end -19.777964 22.649942)
			(stroke
				(width 0.1)
				(type default)
			)
			(layer "F.Fab")
		)
		(fp_line
			(start -18.840958 -24.45004)
			(end -19.777964 -24.45004)
			(stroke
				(width 0.1)
				(type default)
			)
			(layer "F.Fab")
		)
		(fp_line
			(start -18.840958 -29.219906)
			(end -18.840958 -24.45004)
			(stroke
				(width 0.1)
				(type default)
			)
			(layer "F.Fab")
		)
		(fp_line
			(start -19.777964 22.649942)
			(end -18.840958 22.649942)
			(stroke
				(width 0.1)
				(type default)
			)
			(layer "F.Fab")
		)
		(fp_line
			(start -19.777964 22.649942)
			(end -19.777964 15.81658)
			(stroke
				(width 0.1)
				(type default)
			)
			(layer "F.Fab")
		)
		(fp_line
			(start -19.777964 15.81658)
			(end -19.777964 22.649942)
			(stroke
				(width 0.1)
				(type default)
			)
			(layer "F.Fab")
		)
		(fp_line
			(start -19.777964 5.100066)
			(end -19.777964 14.383258)
			(stroke
				(width 0.1)
				(type default)
			)
			(layer "F.Fab")
		)
		(fp_line
			(start -19.777964 -6.89991)
			(end -21.77796 -8.899906)
			(stroke
				(width 0.1)
				(type default)
			)
			(layer "F.Fab")
		)
		(fp_line
			(start -19.777964 -24.45004)
			(end -19.777964 -6.89991)
			(stroke
				(width 0.1)
				(type default)
			)
			(layer "F.Fab")
		)
		(fp_line
			(start -21.77796 30.150054)
			(end -21.77796 7.100062)
			(stroke
				(width 0.1)
				(type default)
			)
			(layer "F.Fab")
		)
		(fp_line
			(start -21.77796 7.100062)
			(end -19.777964 5.100066)
			(stroke
				(width 0.1)
				(type default)
			)
			(layer "F.Fab")
		)
		(fp_line
			(start -21.77796 -8.899906)
			(end -21.77796 -31.949898)
			(stroke
				(width 0.1)
				(type default)
			)
			(layer "F.Fab")
		)
		(fp_line
			(start -21.77796 -31.949898)
			(end -14.777974 -31.949898)
			(stroke
				(width 0.1)
				(type default)
			)
			(layer "F.Fab")
		)
		(fp_arc
			(start -19.777964 15.81658)
			(mid -20.051913 15.099951)
			(end -19.777964 14.383258)
			(stroke
				(width 0.1)
				(type default)
			)
			(layer "F.Fab")
		)
	)
	(footprint ""
		(layer "F.Cu")
		(at 281.178 -75.946 90)
		(property "Reference" "R6D6"
			(at 0 0 90)
			(layer "F.SilkS")
			(hide yes)
			(effects
				(font
					(size 1.27 1.27)
				)
			)
		)
		(property "Value" ""
			(at 0 0 90)
			(layer "F.Fab")
			(effects
				(font
					(size 1.27 1.27)
				)
			)
		)
		(duplicate_pad_numbers_are_jumpers no)
		(fp_rect
			(start -0.2794 -0.1016)
			(end 0.2794 0.9906)
			(stroke
				(width 0)
				(type default)
			)
			(fill no)
			(layer "F.CrtYd")
		)
		(fp_line
			(start 0.2794 -0.1016)
			(end -0.2794 -0.1016)
			(stroke
				(width 0.1)
				(type default)
			)
			(layer "F.Fab")
		)
		(fp_line
			(start -0.2794 -0.1016)
			(end -0.2794 0.9906)
			(stroke
				(width 0.1)
				(type default)
			)
			(layer "F.Fab")
		)
		(fp_line
			(start 0.2794 0.9906)
			(end 0.2794 -0.1016)
			(stroke
				(width 0.1)
				(type default)
			)
			(layer "F.Fab")
		)
		(fp_line
			(start -0.2794 0.9906)
			(end 0.2794 0.9906)
			(stroke
				(width 0.1)
				(type default)
			)
			(layer "F.Fab")
		)
		(pad "1" smd rect
			(at 0 0 90)
			(size 0.508 0.508)
			(layers "F.Cu" "F.Mask" "F.Paste")
			(net "GND")
		)
		(pad "2" smd rect
			(at 0 0.889 90)
			(size 0.508 0.508)
			(layers "F.Cu" "F.Mask" "F.Paste")
			(net "PD_CPU0_TXT_PLTEN")
		)
		(zone
			(layer "F.Cu")
			(hatch none 0.5)
			(connect_pads
				(clearance 0)
			)
			(min_thickness 0.25)
			(keepout
				(tracks allowed)
				(vias not_allowed)
				(pads allowed)
				(copperpour not_allowed)
				(footprints allowed)
			)
			(placement
				(enabled no)
				(sheetname "")
			)
			(fill
				(thermal_gap 0.5)
				(thermal_bridge_width 0.5)
				(island_removal_mode 0)
			)
			(polygon
				(pts
					(xy 281.432 -75.692) (xy 281.813 -75.692) (xy 281.813 -76.2) (xy 281.432 -76.2)
				)
			)
		)
		(zone
			(layer "F.Cu")
			(hatch none 0.5)
			(connect_pads
				(clearance 0)
			)
			(min_thickness 0.25)
			(keepout
				(tracks not_allowed)
				(vias allowed)
				(pads allowed)
				(copperpour not_allowed)
				(footprints allowed)
			)
			(placement
				(enabled no)
				(sheetname "")
			)
			(fill
				(thermal_gap 0.5)
				(thermal_bridge_width 0.5)
				(island_removal_mode 0)
			)
			(polygon
				(pts
					(xy 281.432 -75.692) (xy 281.813 -75.692) (xy 281.813 -76.2) (xy 281.432 -76.2)
				)
			)
		)
	)
)
